# BASEBOARD_FAB2 (Tioga Pass) — schematic netlist excerpt (pin names and nets, part order shuffled) for the footprints in the layout excerpt that follows; sources: Cadence DE-HDL packaged netlist, KiCad conversion of Wiwynn_Tioga_Pass_MB.brd

J1G2  SCONN288_H44441004  SCONN  pkg PIP  page 79
  \12v\(1)  = P12V_NVDIMM_GHJ
  VSS(93)  = GND
  DQ(4)  = M_H_DQ<5>
  VSS(92)  = GND
  DQ(0)  = M_H_DQ<1>
  VSS(91)  = GND
  DQS9P  = M_H_DQS_DP<9>
  DQS9N  = M_H_DQS_DN<9>
  VSS(90)  = GND
  DQ(6)  = M_H_DQ<7>
  VSS(89)  = GND
  DQ(2)  = M_H_DQ<3>
  VSS(88)  = GND
  DQ(12)  = M_H_DQ<13>
  VSS(87)  = GND
  DQ(8)  = M_H_DQ<9>
  VSS(86)  = GND
  DQS10P  = M_H_DQS_DP<10>
  DQS10N  = M_H_DQS_DN<10>
  VSS(85)  = GND
  DQ(14)  = M_H_DQ<15>
  VSS(84)  = GND
  DQ(10)  = M_H_DQ<11>
  VSS(83)  = GND
  DQ(20)  = M_H_DQ<21>
  VSS(82)  = GND
  DQ(16)  = M_H_DQ<17>
  VSS(81)  = GND
  DQS11P  = M_H_DQS_DP<11>
  DQS11N  = M_H_DQS_DN<11>
  VSS(80)  = GND
  DQ(22)  = M_H_DQ<23>
  VSS(79)  = GND
  DQ(18)  = M_H_DQ<19>
  VSS(78)  = GND
  DQ(28)  = M_H_DQ<29>
  VSS(77)  = GND
  DQ(24)  = M_H_DQ<25>
  VSS(76)  = GND
  DQS12P  = M_H_DQS_DP<12>
  DQS12N  = M_H_DQS_DN<12>
  VSS(75)  = GND
  DQ(30)  = M_H_DQ<31>
  VSS(74)  = GND
  DQ(26)  = M_H_DQ<27>
  VSS(73)  = GND
  CB(4)  = M_H_ECC<5>
  VSS(72)  = GND
  CB(0)  = M_H_ECC<1>
  VSS(71)  = GND
  DQS17P  = M_H_DQS_DP<17>
  DQS17N  = M_H_DQS_DN<17>
  VSS(70)  = GND
  CB(6)  = M_H_ECC<7>
  VSS(69)  = GND
  CB(2)  = M_H_ECC<3>
  VSS(68)  = GND
  RESET_N  = M_GHJ_RST_N
  VDD(25)  = PVDDQ_GHJ
  CKE(0)  = M_H_CKE<0>
  VDD(24)  = PVDDQ_GHJ
  ACT_N  = M_H_ACT_N
  BG(0)  = M_H_BG<0>
  VDD(23)  = PVDDQ_GHJ
  A12  = M_H_MA<12>
  A9  = M_H_MA<9>
  VDD(22)  = PVDDQ_GHJ
  A8  = M_H_MA<8>
  A6  = M_H_MA<6>
  VDD(21)  = PVDDQ_GHJ
  A3  = M_H_MA<3>
  A1  = M_H_MA<1>
  VDD(20)  = PVDDQ_GHJ
  CK0P  = M_H_CLK_DP<0>
  CK0N  = M_H_CLK_DN<0>
  VDD(19)  = PVDDQ_GHJ
  VTT(1)  = PVTT_GHJ
  EVENT_N  = FM_DIMM_EVENT_COD_N
  A0  = M_H_MA<0>
  VDD(18)  = PVDDQ_GHJ
  BA(0)  = M_H_BA<0>
  A16_RAS_N  = M_H_MA<16>
  VDD(17)  = PVDDQ_GHJ
  S0_N  = M_H_CS_N<0>
  VDD(16)  = PVDDQ_GHJ
  A15_CAS_N  = M_H_MA<15>
  ODT(0)  = M_H_ODT<0>
  VDD(15)  = PVDDQ_GHJ
  S1_N  = M_H_CS_N<1>
  VDD(14)  = PVDDQ_GHJ
  ODT(1)  = M_H_ODT<1>
  VDD(13)  = PVDDQ_GHJ
  S2_N_C(0)  = M_H_CS_N<2>
  VSS(67)  = GND
  DQ(36)  = M_H_DQ<37>
  VSS(66)  = GND
  DQ(32)  = M_H_DQ<33>
  VSS(65)  = GND
  DQS13P  = M_H_DQS_DP<13>
  DQS13N  = M_H_DQS_DN<13>
  VSS(64)  = GND
  DQ(38)  = M_H_DQ<39>
  VSS(63)  = GND
  DQ(34)  = M_H_DQ<35>
  VSS(62)  = GND
  DQ(44)  = M_H_DQ<45>
  VSS(61)  = GND
  DQ(40)  = M_H_DQ<41>
  VSS(60)  = GND
  DQS14P  = M_H_DQS_DP<14>
  DQS14N  = M_H_DQS_DN<14>
  VSS(59)  = GND
  DQ(46)  = M_H_DQ<47>
  VSS(58)  = GND
  DQ(42)  = M_H_DQ<43>
  VSS(57)  = GND
  DQ(52)  = M_H_DQ<53>
  VSS(56)  = GND
  DQ(48)  = M_H_DQ<49>
  VSS(55)  = GND
  DQS15P  = M_H_DQS_DP<15>
  DQS15N  = M_H_DQS_DN<15>
  VSS(54)  = GND
  DQ(54)  = M_H_DQ<55>
  VSS(53)  = GND
  DQ(50)  = M_H_DQ<51>
  VSS(52)  = GND
  DQ(60)  = M_H_DQ<61>
  VSS(51)  = GND
  DQ(56)  = M_H_DQ<57>
  VSS(50)  = GND
  DQS16P  = M_H_DQS_DP<16>
  DQS16N  = M_H_DQS_DN<16>
  VSS(49)  = GND
  DQ(62)  = M_H_DQ<63>
  VSS(48)  = GND
  DQ(58)  = M_H_DQ<59>
  VSS(47)  = GND
  SA(0)  = GND
  SA(1)  = PVPP_GHJ
  SCL  = SMB_DDR_GHJ_VPP_SCL
  VPP(4)  = PVPP_GHJ
  VPP(3)  = PVPP_GHJ
  RFU(2)  = TP_CH_H_DIMM_H0_RFU_2
  \12v\(0)  = P12V_NVDIMM_GHJ
  VREFCA  = M_H_VREF
  VSS(46)  = GND
  DQ(5)  = M_H_DQ<4>
  VSS(45)  = GND
  DQ(1)  = M_H_DQ<0>
  VSS(44)  = GND
  DQS0N  = M_H_DQS_DN<0>
  DQS0P  = M_H_DQS_DP<0>
  VSS(43)  = GND
  DQ(7)  = M_H_DQ<6>
  VSS(42)  = GND
  DQ(3)  = M_H_DQ<2>
  VSS(41)  = GND
  DQ(13)  = M_H_DQ<12>
  VSS(40)  = GND
  DQ(9)  = M_H_DQ<8>
  VSS(39)  = GND
  DQS1N  = M_H_DQS_DN<1>
  DQS1P  = M_H_DQS_DP<1>
  VSS(38)  = GND
  DQ(15)  = M_H_DQ<14>
  VSS(37)  = GND
  DQ(11)  = M_H_DQ<10>
  VSS(36)  = GND
  DQ(21)  = M_H_DQ<20>
  VSS(35)  = GND
  DQ(17)  = M_H_DQ<16>
  VSS(34)  = GND
  DQS2N  = M_H_DQS_DN<2>
  DQS2P  = M_H_DQS_DP<2>
  VSS(33)  = GND
  DQ(23)  = M_H_DQ<22>
  VSS(32)  = GND
  DQ(19)  = M_H_DQ<18>
  VSS(31)  = GND
  DQ(29)  = M_H_DQ<28>
  VSS(30)  = GND
  DQ(25)  = M_H_DQ<24>
  VSS(29)  = GND
  DQS3N  = M_H_DQS_DN<3>
  DQS3P  = M_H_DQS_DP<3>
  VSS(28)  = GND
  DQ(31)  = M_H_DQ<30>
  VSS(27)  = GND
  DQ(27)  = M_H_DQ<26>
  VSS(26)  = GND
  CB(5)  = M_H_ECC<4>
  VSS(25)  = GND
  CB(1)  = M_H_ECC<0>
  VSS(24)  = GND
  DQS8N  = M_H_DQS_DN<8>
  DQS8P  = M_H_DQS_DP<8>
  VSS(23)  = GND
  CB(7)  = M_H_ECC<6>
  VSS(22)  = GND
  CB(3)  = M_H_ECC<2>
  VSS(21)  = GND
  CKE(1)  = M_H_CKE<1>
  VDD(12)  = PVDDQ_GHJ
  RFU(0)  = TP_CH_H_DIMM_H0_RFU_0
  VDD(11)  = PVDDQ_GHJ
  BG(1)  = M_H_BG<1>
  ALERT_N  = M_H_ALERT_N
  VDD(10)  = PVDDQ_GHJ
  A11  = M_H_MA<11>
  A7  = M_H_MA<7>
  VDD(9)  = PVDDQ_GHJ
  A5  = M_H_MA<5>
  A4  = M_H_MA<4>
  VDD(8)  = PVDDQ_GHJ
  A2  = M_H_MA<2>
  VDD(7)  = PVDDQ_GHJ
  CK1P  = M_H_CLK_DP<1>
  CK1N  = M_H_CLK_DN<1>
  VDD(6)  = PVDDQ_GHJ
  VTT(0)  = PVTT_GHJ
  PAR  = M_H_PAR
  VDD(5)  = PVDDQ_GHJ
  BA(1)  = M_H_BA<1>
  A10  = M_H_MA<10>
  VDD(4)  = PVDDQ_GHJ
  RFU(1)  = TP_CH_H_DIMM_H0_RFU_1
  A14_WE_N  = M_H_MA<14>
  VDD(3)  = PVDDQ_GHJ
  SAVE_N_NC  = FM_ADR_COMPLETE_GHJ_N
  VDD(2)  = PVDDQ_GHJ
  A13  = M_H_MA<13>
  VDD(1)  = PVDDQ_GHJ
  A17  = M_H_MA<17>
  C(2)  = M_H_C<2>
  VDD(0)  = PVDDQ_GHJ
  S3_N_C(1)  = M_H_CS_N<3>
  SA(2)  = GND
  VSS(20)  = GND
  DQ(37)  = M_H_DQ<36>
  VSS(19)  = GND
  DQ(33)  = M_H_DQ<32>
  VSS(18)  = GND
  DQS4N  = M_H_DQS_DN<4>
  DQS4P  = M_H_DQS_DP<4>
  VSS(17)  = GND
  DQ(39)  = M_H_DQ<38>
  VSS(16)  = GND
  DQ(35)  = M_H_DQ<34>
  VSS(15)  = GND
  DQ(45)  = M_H_DQ<44>
  VSS(14)  = GND
  DQ(41)  = M_H_DQ<40>
  VSS(13)  = GND
  DQS5N  = M_H_DQS_DN<5>
  DQS5P  = M_H_DQS_DP<5>
  VSS(12)  = GND
  DQ(47)  = M_H_DQ<46>
  VSS(11)  = GND
  DQ(43)  = M_H_DQ<42>
  VSS(10)  = GND
  DQ(53)  = M_H_DQ<52>
  VSS(9)  = GND
  DQ(49)  = M_H_DQ<48>
  VSS(8)  = GND
  DQS6N  = M_H_DQS_DN<6>
  DQS6P  = M_H_DQS_DP<6>
  VSS(7)  = GND
  DQ(55)  = M_H_DQ<54>
  VSS(6)  = GND
  DQ(51)  = M_H_DQ<50>
  VSS(5)  = GND
  DQ(61)  = M_H_DQ<60>
  VSS(4)  = GND
  DQ(57)  = M_H_DQ<56>
  VSS(3)  = GND
  DQS7N  = M_H_DQS_DN<7>
  DQS7P  = M_H_DQS_DP<7>
  VSS(2)  = GND
  DQ(63)  = M_H_DQ<62>
  VSS(1)  = GND
  DQ(59)  = M_H_DQ<58>
  VSS(0)  = GND
  VDDSPD  = PVPP_GHJ
  SDA  = SMB_DDR_GHJ_VPP_SDA
  VPP(1)  = PVPP_GHJ
  VPP(0)  = PVPP_GHJ
  VPP(2)  = PVPP_GHJ

(kicad_pcb
	(version 20260206)
	(generator "pcbnew")
	(generator_version "10.0")
	(general
		(thickness 1.6)
		(legacy_teardrops no)
	)
	(paper "A4")
	(title_block
		(title "Wiwynn_Tioga_Pass_MB.brd")
		(comment 1 "Tioga Pass / footprint 2141 of 4770 (J1G2), pads 101-151 of 291")
	)
	(layers
		(0 "F.Cu" signal "TOP")
		(4 "In1.Cu" signal "L2GND")
		(6 "In2.Cu" signal "L3")
		(8 "In3.Cu" signal "L4GND")
		(10 "In4.Cu" signal "L5")
		(12 "In5.Cu" signal "L6GND")
		(14 "In6.Cu" signal "L7VCC")
		(16 "In7.Cu" signal "L8VCC")
		(18 "In8.Cu" signal "L9GND")
		(20 "In9.Cu" signal "L10")
		(22 "In10.Cu" signal "L11GND")
		(24 "In11.Cu" signal "L12")
		(26 "In12.Cu" signal "L13GND")
		(2 "B.Cu" signal "BOTTOM")
		(9 "F.Adhes" user "F.Adhesive")
		(11 "B.Adhes" user "B.Adhesive")
		(13 "F.Paste" user "Package Geometry/Pastemask Top")
		(15 "B.Paste" user "Package Geometry/Pastemask Bottom")
		(5 "F.SilkS" user "Ref Des/Silkscreen Top")
		(7 "B.SilkS" user "Ref Des/Silkscreen Bottom")
		(1 "F.Mask" user "Board Geometry/Soldermask Top")
		(3 "B.Mask" user "Board Geometry/Soldermask Bottom")
		(17 "Dwgs.User" user "User.Drawings")
		(19 "Cmts.User" user "User.Comments")
		(21 "Eco1.User" user "User.Eco1")
		(23 "Eco2.User" user "User.Eco2")
		(25 "Edge.Cuts" user "Board Geometry/Outline")
		(27 "Margin" user)
		(31 "F.CrtYd" user "Package Geometry/Place Bound Top")
		(29 "B.CrtYd" user "Package Geometry/Place Bound Bottom")
		(35 "F.Fab" user "Ref Des/Assembly Top")
		(33 "B.Fab" user "Ref Des/Assembly Bottom")
	)
	(footprint ""
		(layer "F.Cu")
		(at 29.699458 -5.822442 90)
		(property "Reference" "J1G2"
			(at 7.104888 34.562542 0)
			(unlocked yes)
			(layer "F.SilkS")
			(effects
				(font
					(size 0.7874 0.5842)
					(thickness 0.1524)
				)
				(justify left)
			)
		)
		(property "Value" ""
			(at 0 0 90)
			(layer "F.Fab")
			(effects
				(font
					(size 1.27 1.27)
				)
			)
		)
		(duplicate_pad_numbers_are_jumpers no)
		(pad "98" smd rect
			(at 0 87.54999 90)
			(size 1.8034 0.508)
			(layers "F.Cu" "F.Mask" "F.Paste")
			(net "GND")
		)
		(pad "99" smd rect
			(at 0 88.399874 90)
			(size 1.8034 0.508)
			(layers "F.Cu" "F.Mask" "F.Paste")
			(net "M_H_DQS_DP<13>")
		)
		(pad "100" smd rect
			(at 0 89.250012 90)
			(size 1.8034 0.508)
			(layers "F.Cu" "F.Mask" "F.Paste")
			(net "M_H_DQS_DN<13>")
		)
		(pad "101" smd rect
			(at 0 90.099896 90)
			(size 1.8034 0.508)
			(layers "F.Cu" "F.Mask" "F.Paste")
			(net "GND")
		)
		(pad "102" smd rect
			(at 0 90.950034 90)
			(size 1.8034 0.508)
			(layers "F.Cu" "F.Mask" "F.Paste")
			(net "M_H_DQ<39>")
		)
		(pad "103" smd rect
			(at 0 91.799918 90)
			(size 1.8034 0.508)
			(layers "F.Cu" "F.Mask" "F.Paste")
			(net "GND")
		)
		(pad "104" smd rect
			(at 0 92.650056 90)
			(size 1.8034 0.508)
			(layers "F.Cu" "F.Mask" "F.Paste")
			(net "M_H_DQ<35>")
		)
		(pad "105" smd rect
			(at 0 93.49994 90)
			(size 1.8034 0.508)
			(layers "F.Cu" "F.Mask" "F.Paste")
			(net "GND")
		)
		(pad "106" smd rect
			(at 0 94.350078 90)
			(size 1.8034 0.508)
			(layers "F.Cu" "F.Mask" "F.Paste")
			(net "M_H_DQ<45>")
		)
		(pad "107" smd rect
			(at 0 95.199962 90)
			(size 1.8034 0.508)
			(layers "F.Cu" "F.Mask" "F.Paste")
			(net "GND")
		)
		(pad "108" smd rect
			(at 0 96.0501 90)
			(size 1.8034 0.508)
			(layers "F.Cu" "F.Mask" "F.Paste")
			(net "M_H_DQ<41>")
		)
		(pad "109" smd rect
			(at 0 96.899984 90)
			(size 1.8034 0.508)
			(layers "F.Cu" "F.Mask" "F.Paste")
			(net "GND")
		)
		(pad "110" smd rect
			(at 0 97.750122 90)
			(size 1.8034 0.508)
			(layers "F.Cu" "F.Mask" "F.Paste")
			(net "M_H_DQS_DP<14>")
		)
		(pad "111" smd rect
			(at 0 98.600006 90)
			(size 1.8034 0.508)
			(layers "F.Cu" "F.Mask" "F.Paste")
			(net "M_H_DQS_DN<14>")
		)
		(pad "112" smd rect
			(at 0 99.44989 90)
			(size 1.8034 0.508)
			(layers "F.Cu" "F.Mask" "F.Paste")
			(net "GND")
		)
		(pad "113" smd rect
			(at 0 100.300028 90)
			(size 1.8034 0.508)
			(layers "F.Cu" "F.Mask" "F.Paste")
			(net "M_H_DQ<47>")
		)
		(pad "114" smd rect
			(at 0 101.149912 90)
			(size 1.8034 0.508)
			(layers "F.Cu" "F.Mask" "F.Paste")
			(net "GND")
		)
		(pad "115" smd rect
			(at 0 102.00005 90)
			(size 1.8034 0.508)
			(layers "F.Cu" "F.Mask" "F.Paste")
			(net "M_H_DQ<43>")
		)
		(pad "116" smd rect
			(at 0 102.849934 90)
			(size 1.8034 0.508)
			(layers "F.Cu" "F.Mask" "F.Paste")
			(net "GND")
		)
		(pad "117" smd rect
			(at 0 103.700072 90)
			(size 1.8034 0.508)
			(layers "F.Cu" "F.Mask" "F.Paste")
			(net "M_H_DQ<53>")
		)
		(pad "118" smd rect
			(at 0 104.549956 90)
			(size 1.8034 0.508)
			(layers "F.Cu" "F.Mask" "F.Paste")
			(net "GND")
		)
		(pad "119" smd rect
			(at 0 105.400094 90)
			(size 1.8034 0.508)
			(layers "F.Cu" "F.Mask" "F.Paste")
			(net "M_H_DQ<49>")
		)
		(pad "120" smd rect
			(at 0 106.249978 90)
			(size 1.8034 0.508)
			(layers "F.Cu" "F.Mask" "F.Paste")
			(net "GND")
		)
		(pad "121" smd rect
			(at 0 107.100116 90)
			(size 1.8034 0.508)
			(layers "F.Cu" "F.Mask" "F.Paste")
			(net "M_H_DQS_DP<15>")
		)
		(pad "122" smd rect
			(at 0 107.95 90)
			(size 1.8034 0.508)
			(layers "F.Cu" "F.Mask" "F.Paste")
			(net "M_H_DQS_DN<15>")
		)
		(pad "123" smd rect
			(at 0 108.799884 90)
			(size 1.8034 0.508)
			(layers "F.Cu" "F.Mask" "F.Paste")
			(net "GND")
		)
		(pad "124" smd rect
			(at 0 109.650022 90)
			(size 1.8034 0.508)
			(layers "F.Cu" "F.Mask" "F.Paste")
			(net "M_H_DQ<55>")
		)
		(pad "125" smd rect
			(at 0 110.499906 90)
			(size 1.8034 0.508)
			(layers "F.Cu" "F.Mask" "F.Paste")
			(net "GND")
		)
		(pad "126" smd rect
			(at 0 111.350044 90)
			(size 1.8034 0.508)
			(layers "F.Cu" "F.Mask" "F.Paste")
			(net "M_H_DQ<51>")
		)
		(pad "127" smd rect
			(at 0 112.199928 90)
			(size 1.8034 0.508)
			(layers "F.Cu" "F.Mask" "F.Paste")
			(net "GND")
		)
		(pad "128" smd rect
			(at 0 113.050066 90)
			(size 1.8034 0.508)
			(layers "F.Cu" "F.Mask" "F.Paste")
			(net "M_H_DQ<61>")
		)
		(pad "129" smd rect
			(at 0 113.89995 90)
			(size 1.8034 0.508)
			(layers "F.Cu" "F.Mask" "F.Paste")
			(net "GND")
		)
		(pad "130" smd rect
			(at 0 114.750088 90)
			(size 1.8034 0.508)
			(layers "F.Cu" "F.Mask" "F.Paste")
			(net "M_H_DQ<57>")
		)
		(pad "131" smd rect
			(at 0 115.599972 90)
			(size 1.8034 0.508)
			(layers "F.Cu" "F.Mask" "F.Paste")
			(net "GND")
		)
		(pad "132" smd rect
			(at 0 116.45011 90)
			(size 1.8034 0.508)
			(layers "F.Cu" "F.Mask" "F.Paste")
			(net "M_H_DQS_DP<16>")
		)
		(pad "133" smd rect
			(at 0 117.299994 90)
			(size 1.8034 0.508)
			(layers "F.Cu" "F.Mask" "F.Paste")
			(net "M_H_DQS_DN<16>")
		)
		(pad "134" smd rect
			(at 0 118.149878 90)
			(size 1.8034 0.508)
			(layers "F.Cu" "F.Mask" "F.Paste")
			(net "GND")
		)
		(pad "135" smd rect
			(at 0 119.000016 90)
			(size 1.8034 0.508)
			(layers "F.Cu" "F.Mask" "F.Paste")
			(net "M_H_DQ<63>")
		)
		(pad "136" smd rect
			(at 0 119.8499 90)
			(size 1.8034 0.508)
			(layers "F.Cu" "F.Mask" "F.Paste")
			(net "GND")
		)
		(pad "137" smd rect
			(at 0 120.700038 90)
			(size 1.8034 0.508)
			(layers "F.Cu" "F.Mask" "F.Paste")
			(net "M_H_DQ<59>")
		)
		(pad "138" smd rect
			(at 0 121.549922 90)
			(size 1.8034 0.508)
			(layers "F.Cu" "F.Mask" "F.Paste")
			(net "GND")
		)
		(pad "139" smd rect
			(at 0 122.40006 90)
			(size 1.8034 0.508)
			(layers "F.Cu" "F.Mask" "F.Paste")
			(net "GND")
		)
		(pad "140" smd rect
			(at 0 123.249944 90)
			(size 1.8034 0.508)
			(layers "F.Cu" "F.Mask" "F.Paste")
			(net "PVPP_GHJ")
		)
		(pad "141" smd rect
			(at 0 124.100082 90)
			(size 1.8034 0.508)
			(layers "F.Cu" "F.Mask" "F.Paste")
			(net "SMB_DDR_GHJ_VPP_SCL")
		)
		(pad "142" smd rect
			(at 0 124.949966 90)
			(size 1.8034 0.508)
			(layers "F.Cu" "F.Mask" "F.Paste")
			(net "PVPP_GHJ")
		)
		(pad "143" smd rect
			(at 0 125.800104 90)
			(size 1.8034 0.508)
			(layers "F.Cu" "F.Mask" "F.Paste")
			(net "PVPP_GHJ")
		)
		(pad "144" smd rect
			(at 0 126.649988 90)
			(size 1.8034 0.508)
			(layers "F.Cu" "F.Mask" "F.Paste")
			(net "TP_CH_H_DIMM_H0_RFU_2")
		)
		(pad "145" smd rect
			(at 4.59994 0 90)
			(size 1.8034 0.508)
			(layers "F.Cu" "F.Mask" "F.Paste")
			(net "P12V_NVDIMM_GHJ")
		)
		(pad "146" smd rect
			(at 4.59994 0.849884 90)
			(size 1.8034 0.508)
			(layers "F.Cu" "F.Mask" "F.Paste")
			(net "M_H_VREF")
		)
		(pad "147" smd rect
			(at 4.59994 1.700022 90)
			(size 1.8034 0.508)
			(layers "F.Cu" "F.Mask" "F.Paste")
			(net "GND")
		)
		(pad "148" smd rect
			(at 4.59994 2.549906 90)
			(size 1.8034 0.508)
			(layers "F.Cu" "F.Mask" "F.Paste")
			(net "M_H_DQ<4>")
		)
	)
)
